(kicad_pcb
	(version 20241229)
	(generator "pcbnew")
	(generator_version "9.0")
	(general
		(thickness 1.61)
		(legacy_teardrops no)
	)
	(paper "A3")
	(title_block
		(title "RDIMM DDR5 Tester")
		(date "2026-05-21")
		(rev "2.2.0")
		(company "Antmicro")
		(comment 9 "footprints 292-298 of 796")
	)
	(layers
		(0 "F.Cu" signal)
		(4 "In1.Cu" power)
		(6 "In2.Cu" mixed)
		(8 "In3.Cu" power)
		(10 "In4.Cu" mixed)
		(12 "In5.Cu" power)
		(14 "In6.Cu" mixed)
		(16 "In7.Cu" power)
		(18 "In8.Cu" power)
		(20 "In9.Cu" mixed)
		(22 "In10.Cu" power)
		(2 "B.Cu" signal)
		(9 "F.Adhes" user "F.Adhesive")
		(11 "B.Adhes" user "B.Adhesive")
		(13 "F.Paste" user)
		(15 "B.Paste" user)
		(5 "F.SilkS" user "F.Silkscreen")
		(7 "B.SilkS" user "B.Silkscreen")
		(1 "F.Mask" user)
		(3 "B.Mask" user)
		(17 "Dwgs.User" user "User.Drawings")
		(19 "Cmts.User" user "User.Comments")
		(21 "Eco1.User" user "User.Eco1")
		(23 "Eco2.User" user "User.Eco2")
		(25 "Edge.Cuts" user)
		(27 "Margin" user)
		(31 "F.CrtYd" user "F.Courtyard")
		(29 "B.CrtYd" user "B.Courtyard")
		(35 "F.Fab" user)
		(33 "B.Fab" user)
	)
	(footprint "antmicro-footprints:antmicro-logo_scaled_30mm"
		(layer "F.Cu")
		(at 155.9 120.89)
		(property "Reference" "G***"
			(at -7.7 -10.3 0)
			(layer "F.SilkS")
			(hide yes)
			(effects
				(font
					(size 1.524 1.524)
					(thickness 0.3)
				)
			)
		)
		(property "Value" "LOGO"
			(at -5.3 10.1 0)
			(layer "F.SilkS")
			(hide yes)
			(effects
				(font
					(size 1.524 1.524)
					(thickness 0.3)
				)
			)
		)
		(attr exclude_from_pos_files exclude_from_bom allow_soldermask_bridges)
	)
	(footprint "antmicro-footprints:R_0603_1608Metric"
		(layer "F.Cu")
		(at 219.78 167.955 90)
		(descr "Resistor SMD 0603")
		(tags "resistor SMD 0603")
		(property "Reference" "R205"
			(at -0.02 -2.505 90)
			(layer "F.SilkS")
			(effects
				(font
					(size 0.7 0.7)
					(thickness 0.15)
				)
				(justify left bottom)
			)
		)
		(property "Value" "R_0R_22.4A_0603"
			(at 0 1.6 90)
			(layer "F.Fab")
			(effects
				(font
					(size 0.7 0.7)
					(thickness 0.15)
				)
				(justify left bottom)
			)
		)
		(property "Datasheet" "https://fscdn.rohm.com/en/products/databook/datasheet/passive/resistor/chip_resistor/pmr-jpw-e.pdf"
			(at 0 0 90)
			(layer "F.Fab")
			(hide yes)
			(effects
				(font
					(size 1.27 1.27)
					(thickness 0.15)
				)
			)
		)
		(property "Manufacturer" "ROHM Semiconductor"
			(at 0 0 90)
			(unlocked yes)
			(layer "F.Fab")
			(hide yes)
			(effects
				(font
					(size 1 1)
					(thickness 0.15)
				)
			)
		)
		(property "MPN" "PMR03EZPJ000"
			(at 0 0 90)
			(unlocked yes)
			(layer "F.Fab")
			(hide yes)
			(effects
				(font
					(size 1 1)
					(thickness 0.15)
				)
			)
		)
		(property "Val" "0R"
			(at 0 0 90)
			(unlocked yes)
			(layer "F.Fab")
			(hide yes)
			(effects
				(font
					(size 1 1)
					(thickness 0.15)
				)
			)
		)
		(property "Author" "Antmicro"
			(at 0 0 90)
			(unlocked yes)
			(layer "F.Fab")
			(hide yes)
			(effects
				(font
					(size 1 1)
					(thickness 0.15)
				)
			)
		)
		(property "License" "Apache-2.0"
			(at 0 0 90)
			(unlocked yes)
			(layer "F.Fab")
			(hide yes)
			(effects
				(font
					(size 1 1)
					(thickness 0.15)
				)
			)
		)
		(property "Max. Curr." "22.4A"
			(at 0 0 90)
			(unlocked yes)
			(layer "F.Fab")
			(hide yes)
			(effects
				(font
					(size 1 1)
					(thickness 0.15)
				)
			)
		)
		(sheetname "/Supply/DC-DC VCCINT/")
		(sheetfile "dc-dc-vccint.kicad_sch")
		(attr smd)
		(fp_line
			(start -0.15 -0.4)
			(end 0.15 -0.4)
			(stroke
				(width 0.15)
				(type solid)
			)
			(layer "F.SilkS")
		)
		(fp_line
			(start -0.15 0.4)
			(end 0.15 0.4)
			(stroke
				(width 0.15)
				(type solid)
			)
			(layer "F.SilkS")
		)
		(fp_rect
			(start -1.25 -0.65)
			(end 1.25 0.65)
			(stroke
				(width 0.05)
				(type solid)
			)
			(fill no)
			(layer "F.CrtYd")
		)
		(fp_rect
			(start -0.8 -0.4)
			(end 0.8 0.4)
			(stroke
				(width 0.15)
				(type solid)
			)
			(fill no)
			(layer "F.Fab")
		)
		(fp_text user "Author: Antmicro"
			(at -1.25 4.9 90)
			(layer "F.Fab")
			(effects
				(font
					(size 0.7 0.7)
					(thickness 0.15)
				)
				(justify left bottom)
			)
		)
		(fp_text user "License: Apache-2.0"
			(at -1.25 5.9 90)
			(layer "F.Fab")
			(effects
				(font
					(size 0.7 0.7)
					(thickness 0.15)
				)
				(justify left bottom)
			)
		)
		(fp_text user "${REFERENCE}"
			(at -1.25 3.898 90)
			(layer "F.Fab")
			(effects
				(font
					(size 0.7 0.7)
					(thickness 0.15)
				)
				(justify left bottom)
			)
		)
		(pad "1" smd roundrect
			(at -0.7 0 90)
			(size 0.8 1)
			(layers "F.Cu" "F.Mask" "F.Paste")
			(roundrect_rratio 0.2)
			(net 223 "/Supply/DC-DC VCCINT/0V85_REG0")
			(pintype "passive")
		)
		(pad "2" smd roundrect
			(at 0.7 0 90)
			(size 0.8 1)
			(layers "F.Cu" "F.Mask" "F.Paste")
			(roundrect_rratio 0.2)
			(net 553 "+0V85")
			(pintype "passive")
		)
	)
	(footprint "antmicro-footprints:TP_SMD_1mm"
		(layer "F.Cu")
		(at 244.024499 173.299)
		(property "Reference" "TP8"
			(at 0 -0.731898 0)
			(layer "F.SilkS")
			(hide yes)
			(effects
				(font
					(size 0.7 0.7)
					(thickness 0.15)
				)
				(justify left bottom)
			)
		)
		(property "Value" "TP_1mm_SMD"
			(at 0 1.4 0)
			(layer "F.Fab")
			(effects
				(font
					(size 0.7 0.7)
					(thickness 0.15)
				)
				(justify left bottom)
			)
		)
		(property "MPN" ""
			(at 0 0 0)
			(unlocked yes)
			(layer "F.Fab")
			(hide yes)
			(effects
				(font
					(size 1 1)
					(thickness 0.15)
				)
			)
		)
		(property "Manufacturer" ""
			(at 0 0 0)
			(unlocked yes)
			(layer "F.Fab")
			(hide yes)
			(effects
				(font
					(size 1 1)
					(thickness 0.15)
				)
			)
		)
		(property "Author" "Antmicro"
			(at 0 0 0)
			(unlocked yes)
			(layer "F.Fab")
			(hide yes)
			(effects
				(font
					(size 1 1)
					(thickness 0.15)
				)
			)
		)
		(property "License" "Apache-2.0"
			(at 0 0 0)
			(unlocked yes)
			(layer "F.Fab")
			(hide yes)
			(effects
				(font
					(size 1 1)
					(thickness 0.15)
				)
			)
		)
		(sheetname "/Supply/DC-DC AUX, MGT/")
		(sheetfile "dc-dc-aux-mgt.kicad_sch")
		(attr exclude_from_pos_files)
		(fp_circle
			(center 0 0)
			(end 0.6 0)
			(stroke
				(width 0.05)
				(type default)
			)
			(fill no)
			(layer "F.CrtYd")
		)
		(fp_text user "${REFERENCE}"
			(at -0.5 2.8 0)
			(layer "F.Fab")
			(effects
				(font
					(size 0.7 0.7)
					(thickness 0.15)
				)
				(justify left bottom)
			)
		)
		(fp_text user "License: Apache-2.0"
			(at -0.5 5.2 0)
			(layer "F.Fab")
			(effects
				(font
					(size 0.7 0.7)
					(thickness 0.15)
				)
				(justify left bottom)
			)
		)
		(fp_text user "Author: Antmicro"
			(at -0.5 4 0)
			(layer "F.Fab")
			(effects
				(font
					(size 0.7 0.7)
					(thickness 0.15)
				)
				(justify left bottom)
			)
		)
		(pad "1" smd circle
			(at 0 0)
			(size 1 1)
			(layers "F.Cu" "F.Mask")
			(net 797 "+1V8")
			(pinfunction "1")
			(pintype "passive")
		)
	)
	(footprint "antmicro-footprints:R_0402_1005Metric"
		(layer "F.Cu")
		(at 244.25 184.399 90)
		(descr "Resistor SMD 0402")
		(tags "resistor SMD 0402")
		(property "Reference" "R75"
			(at 1.15 0.325 90)
			(layer "F.SilkS")
			(effects
				(font
					(size 0.7 0.7)
					(thickness 0.15)
				)
				(justify left bottom)
			)
		)
		(property "Value" "R_200k_0402"
			(at -1.011843 1.772047 90)
			(layer "F.Fab")
			(effects
				(font
					(size 0.7 0.7)
					(thickness 0.15)
				)
				(justify left bottom)
			)
		)
		(property "Datasheet" "https://www.bourns.com/docs/product-datasheets/cr.pdf"
			(at 0 0 90)
			(layer "F.Fab")
			(hide yes)
			(effects
				(font
					(size 1.27 1.27)
					(thickness 0.15)
				)
			)
		)
		(property "MPN" "CR0402-FX-2003GLF"
			(at 0 0 90)
			(unlocked yes)
			(layer "F.Fab")
			(hide yes)
			(effects
				(font
					(size 1 1)
					(thickness 0.15)
				)
			)
		)
		(property "Manufacturer" "Bourns"
			(at 0 0 90)
			(unlocked yes)
			(layer "F.Fab")
			(hide yes)
			(effects
				(font
					(size 1 1)
					(thickness 0.15)
				)
			)
		)
		(property "License" "Apache-2.0"
			(at 0 0 90)
			(unlocked yes)
			(layer "F.Fab")
			(hide yes)
			(effects
				(font
					(size 1 1)
					(thickness 0.15)
				)
			)
		)
		(property "Author" "Antmicro"
			(at 0 0 90)
			(unlocked yes)
			(layer "F.Fab")
			(hide yes)
			(effects
				(font
					(size 1 1)
					(thickness 0.15)
				)
			)
		)
		(property "Val" "200k"
			(at 0 0 90)
			(unlocked yes)
			(layer "F.Fab")
			(hide yes)
			(effects
				(font
					(size 1 1)
					(thickness 0.15)
				)
			)
		)
		(property "Tolerance" "1%"
			(at 0 0 90)
			(unlocked yes)
			(layer "F.Fab")
			(hide yes)
			(effects
				(font
					(size 1 1)
					(thickness 0.15)
				)
			)
		)
		(sheetname "/I^{2}C + I3C/")
		(sheetfile "i2c.kicad_sch")
		(attr smd)
		(fp_rect
			(start -0.925 -0.47)
			(end 0.925 0.47)
			(stroke
				(width 0.05)
				(type default)
			)
			(fill no)
			(layer "F.CrtYd")
		)
		(fp_rect
			(start -0.5 -0.25)
			(end 0.5 0.25)
			(stroke
				(width 0.15)
				(type solid)
			)
			(fill no)
			(layer "F.Fab")
		)
		(fp_text user "${REFERENCE}"
			(at -0.95 3.168 90)
			(layer "F.Fab")
			(effects
				(font
					(size 0.7 0.7)
					(thickness 0.15)
				)
				(justify left bottom)
			)
		)
		(fp_text user "Author: Antmicro"
			(at -0.95 4.169 90)
			(layer "F.Fab")
			(effects
				(font
					(size 0.7 0.7)
					(thickness 0.15)
				)
				(justify left bottom)
			)
		)
		(fp_text user "License: Apache-2.0"
			(at -0.95 5.169 90)
			(layer "F.Fab")
			(effects
				(font
					(size 0.7 0.7)
					(thickness 0.15)
				)
				(justify left bottom)
			)
		)
		(pad "1" smd roundrect
			(at -0.48 0 90)
			(size 0.59 0.64)
			(layers "F.Cu" "F.Mask" "F.Paste")
			(roundrect_rratio 0.25)
			(net 774 "Net-(U49-EN)")
			(pintype "passive")
		)
		(pad "2" smd roundrect
			(at 0.48 0 90)
			(size 0.59 0.64)
			(layers "F.Cu" "F.Mask" "F.Paste")
			(roundrect_rratio 0.25)
			(net 151 "+3V3")
			(pintype "passive")
		)
	)
	(footprint "antmicro-footprints:R_0402_1005Metric"
		(layer "F.Cu")
		(at 161.81 157.199999 90)
		(descr "Resistor SMD 0402")
		(tags "resistor SMD 0402")
		(property "Reference" "R70"
			(at 0.949999 0.46 90)
			(layer "F.SilkS")
			(effects
				(font
					(size 0.7 0.7)
					(thickness 0.15)
				)
				(justify left bottom)
			)
		)
		(property "Value" "R_4k7_0402"
			(at -1.011843 1.772047 90)
			(layer "F.Fab")
			(effects
				(font
					(size 0.7 0.7)
					(thickness 0.15)
				)
				(justify left bottom)
			)
		)
		(property "Datasheet" "https://www.bourns.com/docs/product-datasheets/cr.pdf"
			(at 0 0 90)
			(layer "F.Fab")
			(hide yes)
			(effects
				(font
					(size 1.27 1.27)
					(thickness 0.15)
				)
			)
		)
		(property "MPN" "CR0402-FX-4701GLF"
			(at 0 0 90)
			(unlocked yes)
			(layer "F.Fab")
			(hide yes)
			(effects
				(font
					(size 1 1)
					(thickness 0.15)
				)
			)
		)
		(property "Manufacturer" "Bourns"
			(at 0 0 90)
			(unlocked yes)
			(layer "F.Fab")
			(hide yes)
			(effects
				(font
					(size 1 1)
					(thickness 0.15)
				)
			)
		)
		(property "License" "Apache-2.0"
			(at 0 0 90)
			(unlocked yes)
			(layer "F.Fab")
			(hide yes)
			(effects
				(font
					(size 1 1)
					(thickness 0.15)
				)
			)
		)
		(property "Author" "Antmicro"
			(at 0 0 90)
			(unlocked yes)
			(layer "F.Fab")
			(hide yes)
			(effects
				(font
					(size 1 1)
					(thickness 0.15)
				)
			)
		)
		(property "Val" "4k7"
			(at 0 0 90)
			(unlocked yes)
			(layer "F.Fab")
			(hide yes)
			(effects
				(font
					(size 1 1)
					(thickness 0.15)
				)
			)
		)
		(property "Tolerance" "1%"
			(at 0 0 90)
			(unlocked yes)
			(layer "F.Fab")
			(hide yes)
			(effects
				(font
					(size 1 1)
					(thickness 0.15)
				)
			)
		)
		(sheetname "/FPGA MGT Interface/")
		(sheetfile "fpga-mgt.kicad_sch")
		(attr smd)
		(fp_rect
			(start -0.925 -0.47)
			(end 0.925 0.47)
			(stroke
				(width 0.05)
				(type default)
			)
			(fill no)
			(layer "F.CrtYd")
		)
		(fp_rect
			(start -0.5 -0.25)
			(end 0.5 0.25)
			(stroke
				(width 0.15)
				(type solid)
			)
			(fill no)
			(layer "F.Fab")
		)
		(fp_text user "License: Apache-2.0"
			(at -0.95 5.169 90)
			(layer "F.Fab")
			(effects
				(font
					(size 0.7 0.7)
					(thickness 0.15)
				)
				(justify left bottom)
			)
		)
		(fp_text user "${REFERENCE}"
			(at -0.95 3.168 90)
			(layer "F.Fab")
			(effects
				(font
					(size 0.7 0.7)
					(thickness 0.15)
				)
				(justify left bottom)
			)
		)
		(fp_text user "Author: Antmicro"
			(at -0.95 4.169 90)
			(layer "F.Fab")
			(effects
				(font
					(size 0.7 0.7)
					(thickness 0.15)
				)
				(justify left bottom)
			)
		)
		(pad "1" smd roundrect
			(at -0.48 0 90)
			(size 0.59 0.64)
			(layers "F.Cu" "F.Mask" "F.Paste")
			(roundrect_rratio 0.25)
			(net 531 "~{SI_5319_RST}")
			(pintype "passive")
		)
		(pad "2" smd roundrect
			(at 0.48 0 90)
			(size 0.59 0.64)
			(layers "F.Cu" "F.Mask" "F.Paste")
			(roundrect_rratio 0.25)
			(net 151 "+3V3")
			(pintype "passive")
		)
	)
	(footprint "antmicro-footprints:TP_SMD_1mm"
		(layer "F.Cu")
		(at 224.325 167.4)
		(property "Reference" "TP17"
			(at 0 -0.731898 0)
			(layer "F.SilkS")
			(hide yes)
			(effects
				(font
					(size 0.7 0.7)
					(thickness 0.15)
				)
				(justify left bottom)
			)
		)
		(property "Value" "TP_1mm_SMD"
			(at 0 1.4 0)
			(layer "F.Fab")
			(effects
				(font
					(size 0.7 0.7)
					(thickness 0.15)
				)
				(justify left bottom)
			)
		)
		(property "MPN" ""
			(at 0 0 0)
			(unlocked yes)
			(layer "F.Fab")
			(hide yes)
			(effects
				(font
					(size 1 1)
					(thickness 0.15)
				)
			)
		)
		(property "Manufacturer" ""
			(at 0 0 0)
			(unlocked yes)
			(layer "F.Fab")
			(hide yes)
			(effects
				(font
					(size 1 1)
					(thickness 0.15)
				)
			)
		)
		(property "Author" "Antmicro"
			(at 0 0 0)
			(unlocked yes)
			(layer "F.Fab")
			(hide yes)
			(effects
				(font
					(size 1 1)
					(thickness 0.15)
				)
			)
		)
		(property "License" "Apache-2.0"
			(at 0 0 0)
			(unlocked yes)
			(layer "F.Fab")
			(hide yes)
			(effects
				(font
					(size 1 1)
					(thickness 0.15)
				)
			)
		)
		(sheetname "/Supply/DC-DC VCCINT/")
		(sheetfile "dc-dc-vccint.kicad_sch")
		(attr exclude_from_pos_files)
		(fp_circle
			(center 0 0)
			(end 0.6 0)
			(stroke
				(width 0.05)
				(type default)
			)
			(fill no)
			(layer "F.CrtYd")
		)
		(fp_text user "${REFERENCE}"
			(at -0.5 2.8 0)
			(layer "F.Fab")
			(effects
				(font
					(size 0.7 0.7)
					(thickness 0.15)
				)
				(justify left bottom)
			)
		)
		(fp_text user "Author: Antmicro"
			(at -0.5 4 0)
			(layer "F.Fab")
			(effects
				(font
					(size 0.7 0.7)
					(thickness 0.15)
				)
				(justify left bottom)
			)
		)
		(fp_text user "License: Apache-2.0"
			(at -0.5 5.2 0)
			(layer "F.Fab")
			(effects
				(font
					(size 0.7 0.7)
					(thickness 0.15)
				)
				(justify left bottom)
			)
		)
		(pad "1" smd circle
			(at 0 0)
			(size 1 1)
			(layers "F.Cu" "F.Mask")
			(net 553 "+0V85")
			(pinfunction "1")
			(pintype "passive")
		)
	)
	(footprint "antmicro-footprints:R_0402_1005Metric"
		(layer "F.Cu")
		(at 215.179999 180.665 -90)
		(descr "Resistor SMD 0402")
		(tags "resistor SMD 0402")
		(property "Reference" "R196"
			(at 1.245 -0.340001 90)
			(layer "F.SilkS")
			(effects
				(font
					(size 0.7 0.7)
					(thickness 0.15)
				)
				(justify right bottom)
			)
		)
		(property "Value" "R_10R_0402"
			(at -1.011843 1.772047 90)
			(layer "F.Fab")
			(effects
				(font
					(size 0.7 0.7)
					(thickness 0.15)
				)
				(justify right bottom)
			)
		)
		(property "Datasheet" "https://www.bourns.com/docs/product-datasheets/cr.pdf"
			(at 0 0 270)
			(layer "F.Fab")
			(hide yes)
			(effects
				(font
					(size 1.27 1.27)
					(thickness 0.15)
				)
			)
		)
		(property "MPN" "CR0402-FX-10R0GLF"
			(at 0 0 270)
			(unlocked yes)
			(layer "F.Fab")
			(hide yes)
			(effects
				(font
					(size 1 1)
					(thickness 0.15)
				)
			)
		)
		(property "Manufacturer" "Bourns"
			(at 0 0 270)
			(unlocked yes)
			(layer "F.Fab")
			(hide yes)
			(effects
				(font
					(size 1 1)
					(thickness 0.15)
				)
			)
		)
		(property "License" "Apache-2.0"
			(at 0 0 270)
			(unlocked yes)
			(layer "F.Fab")
			(hide yes)
			(effects
				(font
					(size 1 1)
					(thickness 0.15)
				)
			)
		)
		(property "Author" "Antmicro"
			(at 0 0 270)
			(unlocked yes)
			(layer "F.Fab")
			(hide yes)
			(effects
				(font
					(size 1 1)
					(thickness 0.15)
				)
			)
		)
		(property "Val" "10R"
			(at 0 0 270)
			(unlocked yes)
			(layer "F.Fab")
			(hide yes)
			(effects
				(font
					(size 1 1)
					(thickness 0.15)
				)
			)
		)
		(property "Tolerance" "1%"
			(at 0 0 270)
			(unlocked yes)
			(layer "F.Fab")
			(hide yes)
			(effects
				(font
					(size 1 1)
					(thickness 0.15)
				)
			)
		)
		(sheetname "/Supply/DC-DC VCCINT/")
		(sheetfile "dc-dc-vccint.kicad_sch")
		(attr smd)
		(fp_rect
			(start -0.925 -0.47)
			(end 0.925 0.47)
			(stroke
				(width 0.05)
				(type default)
			)
			(fill no)
			(layer "F.CrtYd")
		)
		(fp_rect
			(start -0.5 -0.25)
			(end 0.5 0.25)
			(stroke
				(width 0.15)
				(type solid)
			)
			(fill no)
			(layer "F.Fab")
		)
		(fp_text user "License: Apache-2.0"
			(at -0.95 5.169 270)
			(layer "F.Fab")
			(effects
				(font
					(size 0.7 0.7)
					(thickness 0.15)
				)
				(justify left bottom)
			)
		)
		(fp_text user "Author: Antmicro"
			(at -0.95 4.169 270)
			(layer "F.Fab")
			(effects
				(font
					(size 0.7 0.7)
					(thickness 0.15)
				)
				(justify left bottom)
			)
		)
		(fp_text user "${REFERENCE}"
			(at -0.95 3.168 270)
			(layer "F.Fab")
			(effects
				(font
					(size 0.7 0.7)
					(thickness 0.15)
				)
				(justify left bottom)
			)
		)
		(pad "1" smd roundrect
			(at -0.48 0 270)
			(size 0.59 0.64)
			(layers "F.Cu" "F.Mask" "F.Paste")
			(roundrect_rratio 0.25)
			(net 222 "Net-(U4-V_{DRV})")
			(pintype "passive")
		)
		(pad "2" smd roundrect
			(at 0.48 0 270)
			(size 0.59 0.64)
			(layers "F.Cu" "F.Mask" "F.Paste")
			(roundrect_rratio 0.25)
			(net 163 "/Supply/DC-DC VCCINT/V_{CC}")
			(pintype "passive")
		)
	)
)
